(kicad_pcb
	(version 20241229)
	(generator "pcbnew")
	(generator_version "9.0")
	(general
		(thickness 1.711)
		(legacy_teardrops no)
	)
	(paper "A4")
	(title_block
		(title "Antmicro Baseboard for Jetson AGX Thor")
		(date "2026-02-18")
		(rev "1.1.0")
		(company "Antmicro Ltd")
		(comment 1 "www.antmicro.com")
		(comment 9 "footprint 425 of 1170 (U21), pads 70-101 of 101")
	)
	(layers
		(0 "F.Cu" signal)
		(4 "In1.Cu" signal)
		(6 "In2.Cu" signal)
		(8 "In3.Cu" signal)
		(10 "In4.Cu" jumper)
		(12 "In5.Cu" signal)
		(14 "In6.Cu" signal)
		(16 "In7.Cu" signal)
		(18 "In8.Cu" signal)
		(2 "B.Cu" signal)
		(9 "F.Adhes" user "F.Adhesive")
		(11 "B.Adhes" user "B.Adhesive")
		(13 "F.Paste" user)
		(15 "B.Paste" user)
		(5 "F.SilkS" user "F.Silkscreen")
		(7 "B.SilkS" user "B.Silkscreen")
		(1 "F.Mask" user)
		(3 "B.Mask" user)
		(17 "Dwgs.User" user "User.Drawings")
		(19 "Cmts.User" user "User.Comments")
		(21 "Eco1.User" user "User.Eco1")
		(23 "Eco2.User" user "User.Eco2")
		(25 "Edge.Cuts" user)
		(27 "Margin" user)
		(31 "F.CrtYd" user "F.Courtyard")
		(29 "B.CrtYd" user "B.Courtyard")
		(35 "F.Fab" user)
		(33 "B.Fab" user)
	)
	(footprint "antmicro-footprints:VQFN-100-1EP_12x12x0.85mm_P0.4mm"
		(layer "F.Cu")
		(at 205.353 125.699 180)
		(property "Reference" "U21"
			(at 6.653 6.699 180)
			(layer "F.SilkS")
			(effects
				(font
					(size 0.7 0.7)
					(thickness 0.15)
				)
				(justify left bottom)
			)
		)
		(property "Value" "USB7252C"
			(at 0 7.6 0)
			(layer "F.Fab")
			(effects
				(font
					(size 0.7 0.7)
					(thickness 0.15)
				)
				(justify right top)
			)
		)
		(property "Datasheet" "https://ww1.microchip.com/downloads/en/DeviceDoc/00003852A.pdf"
			(at 0 0 0)
			(layer "F.Fab")
			(hide yes)
			(effects
				(font
					(size 1.27 1.27)
					(thickness 0.15)
				)
			)
		)
		(property "Description" "4-Port USB 3.2 Hub, 2x Type-C with Power Delivery support, 1x USB 3.2, 1x USB 2.0"
			(at 0 0 0)
			(layer "F.Fab")
			(hide yes)
			(effects
				(font
					(size 1.27 1.27)
					(thickness 0.15)
				)
			)
		)
		(property "MPN" "USB7252CT-I/KDX "
			(at 0 0 180)
			(unlocked yes)
			(layer "F.Fab")
			(hide yes)
			(effects
				(font
					(size 1 1)
					(thickness 0.15)
				)
			)
		)
		(property "Manufacturer" "Microchip Technology"
			(at 0 0 180)
			(unlocked yes)
			(layer "F.Fab")
			(hide yes)
			(effects
				(font
					(size 1 1)
					(thickness 0.15)
				)
			)
		)
		(property "Author" "Antmicro"
			(at 0 0 180)
			(unlocked yes)
			(layer "F.Fab")
			(hide yes)
			(effects
				(font
					(size 1 1)
					(thickness 0.15)
				)
			)
		)
		(property "License" "Apache-2.0"
			(at 0 0 180)
			(unlocked yes)
			(layer "F.Fab")
			(hide yes)
			(effects
				(font
					(size 1 1)
					(thickness 0.15)
				)
			)
		)
		(sheetname "/USB Hub/")
		(sheetfile "usb_hub.kicad_sch")
		(attr smd)
		(pad "70" smd roundrect
			(at 5.788 -2.801 270)
			(size 0.204 1.011199)
			(layers "F.Cu" "F.Mask" "F.Paste")
			(roundrect_rratio 0.25)
			(net 925 "/USB Hub/HUB_SPI_D0")
			(pinfunction "SPI_D0")
			(pintype "bidirectional")
		)
		(pad "71" smd roundrect
			(at 5.788 -3.201 270)
			(size 0.204 1.011199)
			(layers "F.Cu" "F.Mask" "F.Paste")
			(roundrect_rratio 0.25)
			(net 922 "/USB Hub/HUB_SPI_D1")
			(pinfunction "SPI_D1")
			(pintype "bidirectional")
		)
		(pad "72" smd roundrect
			(at 5.788 -3.601 270)
			(size 0.204 1.011199)
			(layers "F.Cu" "F.Mask" "F.Paste")
			(roundrect_rratio 0.25)
			(net 921 "/USB Hub/HUB_SPI_D2")
			(pinfunction "SPI_D2")
			(pintype "bidirectional")
		)
		(pad "73" smd roundrect
			(at 5.788 -4 270)
			(size 0.204 1.011199)
			(layers "F.Cu" "F.Mask" "F.Paste")
			(roundrect_rratio 0.25)
			(net 924 "/USB Hub/HUB_SPI_D3")
			(pinfunction "SPI_D3")
			(pintype "bidirectional")
		)
		(pad "74" smd roundrect
			(at 5.788 -4.401 270)
			(size 0.204 1.011199)
			(layers "F.Cu" "F.Mask" "F.Paste")
			(roundrect_rratio 0.25)
			(net 1083 "unconnected-(U21-PF29-Pad74)")
			(pinfunction "PF29")
			(pintype "bidirectional+no_connect")
		)
		(pad "75" smd roundrect
			(at 5.788 -4.8 270)
			(size 0.204 1.011199)
			(layers "F.Cu" "F.Mask" "F.Paste")
			(roundrect_rratio 0.25)
			(net 1234 "Net-(U21-PF26)")
			(pinfunction "PF26")
			(pintype "bidirectional")
		)
		(pad "76" smd roundrect
			(at 4.799 -5.789 180)
			(size 0.204 1.011199)
			(layers "F.Cu" "F.Mask" "F.Paste")
			(roundrect_rratio 0.25)
			(net 1093 "unconnected-(U21-PF27-Pad76)")
			(pinfunction "PF27")
			(pintype "bidirectional+no_connect")
		)
		(pad "77" smd roundrect
			(at 4.398 -5.789 180)
			(size 0.204 1.011199)
			(layers "F.Cu" "F.Mask" "F.Paste")
			(roundrect_rratio 0.25)
			(net 1102 "unconnected-(U21-PF28-Pad77)")
			(pinfunction "PF28")
			(pintype "bidirectional+no_connect")
		)
		(pad "78" smd roundrect
			(at 3.999 -5.789 180)
			(size 0.204 1.011199)
			(layers "F.Cu" "F.Mask" "F.Paste")
			(roundrect_rratio 0.25)
			(net 282 "+1V15")
			(pinfunction "VCORE")
			(pintype "power_in")
		)
		(pad "79" smd roundrect
			(at 3.6 -5.789 180)
			(size 0.204 1.011199)
			(layers "F.Cu" "F.Mask" "F.Paste")
			(roundrect_rratio 0.25)
			(net 2 "+3V3")
			(pinfunction "VDD33")
			(pintype "power_in")
		)
		(pad "80" smd roundrect
			(at 3.199 -5.789 180)
			(size 0.204 1.011199)
			(layers "F.Cu" "F.Mask" "F.Paste")
			(roundrect_rratio 0.25)
			(net 1164 "/USB Hub/VBUS_MON_UP")
			(pinfunction "VBUS_MON_UP")
			(pintype "bidirectional")
		)
		(pad "81" smd roundrect
			(at 2.798 -5.789 180)
			(size 0.204 1.011199)
			(layers "F.Cu" "F.Mask" "F.Paste")
			(roundrect_rratio 0.25)
			(net 1111 "Net-(U21-USB2DN_DP3)")
			(pinfunction "USB2DN_DP3")
			(pintype "bidirectional")
		)
		(pad "82" smd roundrect
			(at 2.398 -5.789 180)
			(size 0.204 1.011199)
			(layers "F.Cu" "F.Mask" "F.Paste")
			(roundrect_rratio 0.25)
			(net 1126 "Net-(U21-USB2DN_DM3)")
			(pinfunction "USB2DN_DM3")
			(pintype "bidirectional")
		)
		(pad "83" smd roundrect
			(at 1.999 -5.789 180)
			(size 0.204 1.011199)
			(layers "F.Cu" "F.Mask" "F.Paste")
			(roundrect_rratio 0.25)
			(net 1091 "unconnected-(U21-USB3DN_TXDP3-Pad83)")
			(pinfunction "USB3DN_TXDP3")
			(pintype "bidirectional+no_connect")
		)
		(pad "84" smd roundrect
			(at 1.598 -5.789 180)
			(size 0.204 1.011199)
			(layers "F.Cu" "F.Mask" "F.Paste")
			(roundrect_rratio 0.25)
			(net 1080 "unconnected-(U21-USB3DN_TXDM3-Pad84)")
			(pinfunction "USB3DN_TXDM3")
			(pintype "bidirectional+no_connect")
		)
		(pad "85" smd roundrect
			(at 1.199 -5.789 180)
			(size 0.204 1.011199)
			(layers "F.Cu" "F.Mask" "F.Paste")
			(roundrect_rratio 0.25)
			(net 282 "+1V15")
			(pinfunction "VCORE")
			(pintype "power_in")
		)
		(pad "86" smd roundrect
			(at 0.8 -5.789 180)
			(size 0.204 1.011199)
			(layers "F.Cu" "F.Mask" "F.Paste")
			(roundrect_rratio 0.25)
			(net 1142 "Net-(U21-USB3DN_RXDP3)")
			(pinfunction "USB3DN_RXDP3")
			(pintype "bidirectional")
		)
		(pad "87" smd roundrect
			(at 0.399 -5.789 180)
			(size 0.204 1.011199)
			(layers "F.Cu" "F.Mask" "F.Paste")
			(roundrect_rratio 0.25)
			(net 1163 "Net-(U21-USB3DN_RXDM3)")
			(pinfunction "USB3DN_RXDM3")
			(pintype "bidirectional")
		)
		(pad "88" smd roundrect
			(at 0 -5.789 180)
			(size 0.204 1.011199)
			(layers "F.Cu" "F.Mask" "F.Paste")
			(roundrect_rratio 0.25)
			(net 2 "+3V3")
			(pinfunction "VDD33")
			(pintype "power_in")
		)
		(pad "89" smd roundrect
			(at -0.401 -5.789 180)
			(size 0.204 1.011199)
			(layers "F.Cu" "F.Mask" "F.Paste")
			(roundrect_rratio 0.25)
			(net 492 "/SoM_IO2/USB2.D+")
			(pinfunction "USB2UP_DP")
			(pintype "bidirectional")
		)
		(pad "90" smd roundrect
			(at -0.802 -5.789 180)
			(size 0.204 1.011199)
			(layers "F.Cu" "F.Mask" "F.Paste")
			(roundrect_rratio 0.25)
			(net 493 "/SoM_IO2/USB2.D-")
			(pinfunction "USB2UP_DM")
			(pintype "bidirectional")
		)
		(pad "91" smd roundrect
			(at -1.2 -5.789 180)
			(size 0.204 1.011199)
			(layers "F.Cu" "F.Mask" "F.Paste")
			(roundrect_rratio 0.25)
			(net 1132 "/USB Hub/USBSS_TX_P")
			(pinfunction "USB3UP_TXDP")
			(pintype "bidirectional")
		)
		(pad "92" smd roundrect
			(at -1.601 -5.789 180)
			(size 0.204 1.011199)
			(layers "F.Cu" "F.Mask" "F.Paste")
			(roundrect_rratio 0.25)
			(net 1134 "/USB Hub/USBSS_TX_N")
			(pinfunction "USB3UP_TXDM")
			(pintype "bidirectional")
		)
		(pad "93" smd roundrect
			(at -2 -5.789 180)
			(size 0.204 1.011199)
			(layers "F.Cu" "F.Mask" "F.Paste")
			(roundrect_rratio 0.25)
			(net 282 "+1V15")
			(pinfunction "VCORE")
			(pintype "power_in")
		)
		(pad "94" smd roundrect
			(at -2.4 -5.789 180)
			(size 0.204 1.011199)
			(layers "F.Cu" "F.Mask" "F.Paste")
			(roundrect_rratio 0.25)
			(net 1133 "/USB Hub/USBSS_RX_P")
			(pinfunction "USB3UP_RXDP")
			(pintype "bidirectional")
		)
		(pad "95" smd roundrect
			(at -2.801 -5.789 180)
			(size 0.204 1.011199)
			(layers "F.Cu" "F.Mask" "F.Paste")
			(roundrect_rratio 0.25)
			(net 1135 "/USB Hub/USBSS_RX_N")
			(pinfunction "USB3UP_RXDM")
			(pintype "bidirectional")
		)
		(pad "96" smd roundrect
			(at -3.201 -5.789 180)
			(size 0.204 1.011199)
			(layers "F.Cu" "F.Mask" "F.Paste")
			(roundrect_rratio 0.25)
			(net 1079 "unconnected-(U21-ATEST-Pad96)")
			(pinfunction "ATEST")
			(pintype "no_connect")
		)
		(pad "97" smd roundrect
			(at -3.601 -5.789 180)
			(size 0.204 1.011199)
			(layers "F.Cu" "F.Mask" "F.Paste")
			(roundrect_rratio 0.25)
			(net 1087 "unconnected-(U21-XTALO-Pad97)")
			(pinfunction "XTALO")
			(pintype "output+no_connect")
		)
		(pad "98" smd roundrect
			(at -4 -5.789 180)
			(size 0.204 1.011199)
			(layers "F.Cu" "F.Mask" "F.Paste")
			(roundrect_rratio 0.25)
			(net 1078 "Net-(U21-XTALI)")
			(pinfunction "XTALI")
			(pintype "input")
		)
		(pad "99" smd roundrect
			(at -4.401 -5.789 180)
			(size 0.204 1.011199)
			(layers "F.Cu" "F.Mask" "F.Paste")
			(roundrect_rratio 0.25)
			(net 2 "+3V3")
			(pinfunction "VDD33")
			(pintype "power_in")
		)
		(pad "100" smd roundrect
			(at -4.8 -5.789 180)
			(size 0.204 1.011199)
			(layers "F.Cu" "F.Mask" "F.Paste")
			(roundrect_rratio 0.25)
			(net 919 "Net-(U21-RBIAS)")
			(pinfunction "RBIAS")
			(pintype "input")
		)
		(pad "101" smd roundrect
			(at 0 0 180)
			(size 8.1026 8.1026)
			(layers "F.Cu" "F.Mask")
			(roundrect_rratio 0.05)
			(net 1 "GND")
			(pinfunction "VSS")
			(pintype "power_in")
		)
	)
)
